(kicad_pcb
	(version 20260206)
	(generator "pcbnew")
	(generator_version "10.0")
	(general
		(thickness 1.6)
		(legacy_teardrops no)
	)
	(paper "A4")
	(title_block
		(title "panther-plus-userver — 13130-1b_20150205.brd")
		(comment 1 "Honey Badger (Wiwynn) / footprints 121-128 of 1509")
	)
	(layers
		(0 "F.Cu" signal "TOP")
		(4 "In1.Cu" signal "L2")
		(6 "In2.Cu" signal "L3")
		(8 "In3.Cu" signal "L4")
		(10 "In4.Cu" signal "L5")
		(12 "In5.Cu" signal "L6")
		(14 "In6.Cu" signal "L7")
		(16 "In7.Cu" signal "L8")
		(18 "In8.Cu" signal "L9")
		(20 "In9.Cu" signal "L10")
		(22 "In10.Cu" signal "L11")
		(2 "B.Cu" signal "BOTTOM")
		(9 "F.Adhes" user "F.Adhesive")
		(11 "B.Adhes" user "B.Adhesive")
		(13 "F.Paste" user "Package Geometry/Pastemask Top")
		(15 "B.Paste" user "Package Geometry/Pastemask Bottom")
		(5 "F.SilkS" user "Ref Des/Silkscreen Top")
		(7 "B.SilkS" user "Ref Des/Silkscreen Bottom")
		(1 "F.Mask" user "Board Geometry/Soldermask Top")
		(3 "B.Mask" user "Board Geometry/Soldermask Bottom")
		(17 "Dwgs.User" user "User.Drawings")
		(19 "Cmts.User" user "User.Comments")
		(21 "Eco1.User" user "User.Eco1")
		(23 "Eco2.User" user "User.Eco2")
		(25 "Edge.Cuts" user "Board Geometry/Outline")
		(27 "Margin" user)
		(31 "F.CrtYd" user "Package Geometry/Place Bound Top")
		(29 "B.CrtYd" user "Package Geometry/Place Bound Bottom")
		(35 "F.Fab" user "Ref Des/Assembly Top")
		(33 "B.Fab" user "Ref Des/Assembly Bottom")
	)
	(footprint ""
		(layer "F.Cu")
		(at 174.117 -57.15)
		(property "Reference" "R192"
			(at 0 0 0)
			(layer "F.SilkS")
			(hide yes)
			(effects
				(font
					(size 1.27 1.27)
				)
			)
		)
		(property "Value" "4K7R2F-GP"
			(at 0.064008 -3.993896 0)
			(unlocked yes)
			(layer "F.Fab")
			(hide yes)
			(effects
				(font
					(size 1.016 1.016)
					(thickness 0.1524)
				)
			)
		)
		(property "Device Type" "R402H16"
			(at 0.064008 -5.517896 0)
			(unlocked yes)
			(layer "F.Fab")
			(hide yes)
			(effects
				(font
					(size 1.016 1.016)
					(thickness 0.1524)
				)
			)
		)
		(duplicate_pad_numbers_are_jumpers no)
		(fp_rect
			(start -0.381 0.8382)
			(end 0.381 -0.8382)
			(stroke
				(width 0)
				(type default)
			)
			(fill no)
			(layer "F.CrtYd")
		)
		(fp_rect
			(start -0.381 0.8382)
			(end 0.381 -0.8382)
			(stroke
				(width 0)
				(type default)
			)
			(fill no)
			(layer "F.Fab")
		)
		(pad "1" smd custom
			(at 0 -0.4318)
			(size 0.127 0.127)
			(layers "F.Cu" "F.Mask" "F.Paste")
			(net "P3V3_STBY")
			(options
				(clearance outline)
				(anchor circle)
			)
			(primitives
				(gr_poly
					(pts
						(arc
							(start -0.2032 -0.2794)
							(mid -0.239121 -0.264521)
							(end -0.254 -0.2286)
						)
						(arc
							(start -0.254 0.2286)
							(mid -0.239121 0.264521)
							(end -0.2032 0.2794)
						)
						(arc
							(start 0.2032 0.2794)
							(mid 0.239121 0.264521)
							(end 0.254 0.2286)
						)
						(arc
							(start 0.254 -0.2286)
							(mid 0.239121 -0.264521)
							(end 0.2032 -0.2794)
						)
					)
					(width 0)
					(fill yes)
				)
			)
		)
		(pad "2" smd custom
			(at 0 0.4318)
			(size 0.127 0.127)
			(layers "F.Cu" "F.Mask" "F.Paste")
			(net "EEPROM_A2")
			(options
				(clearance outline)
				(anchor circle)
			)
			(primitives
				(gr_poly
					(pts
						(arc
							(start -0.2032 -0.2794)
							(mid -0.239121 -0.264521)
							(end -0.254 -0.2286)
						)
						(arc
							(start -0.254 0.2286)
							(mid -0.239121 0.264521)
							(end -0.2032 0.2794)
						)
						(arc
							(start 0.2032 0.2794)
							(mid 0.239121 0.264521)
							(end 0.254 0.2286)
						)
						(arc
							(start 0.254 -0.2286)
							(mid 0.239121 -0.264521)
							(end 0.2032 -0.2794)
						)
					)
					(width 0)
					(fill yes)
				)
			)
		)
	)
	(footprint ""
		(layer "F.Cu")
		(at 12.9286 -62.8396 -90)
		(property "Reference" "PR39"
			(at 0 0 270)
			(layer "F.SilkS")
			(hide yes)
			(effects
				(font
					(size 1.27 1.27)
				)
			)
		)
		(property "Value" "100R2F-L1-GP-U"
			(at 1.7907 -1.1176 270)
			(unlocked yes)
			(layer "F.Fab")
			(hide yes)
			(effects
				(font
					(size 1.016 1.016)
					(thickness 0.1524)
				)
			)
		)
		(property "Device Type" "R402H14"
			(at 1.7907 -2.6416 270)
			(unlocked yes)
			(layer "F.Fab")
			(hide yes)
			(effects
				(font
					(size 1.016 1.016)
					(thickness 0.1524)
				)
			)
		)
		(duplicate_pad_numbers_are_jumpers no)
		(fp_rect
			(start -0.381 0.8382)
			(end 0.381 -0.8382)
			(stroke
				(width 0)
				(type default)
			)
			(fill no)
			(layer "F.CrtYd")
		)
		(fp_rect
			(start -0.381 0.8382)
			(end 0.381 -0.8382)
			(stroke
				(width 0)
				(type default)
			)
			(fill no)
			(layer "F.Fab")
		)
		(pad "1" smd custom
			(at 0 -0.4318 270)
			(size 0.127 0.127)
			(layers "F.Cu" "F.Mask" "F.Paste")
			(net "SVID_CPU_DATA")
			(options
				(clearance outline)
				(anchor circle)
			)
			(primitives
				(gr_poly
					(pts
						(arc
							(start -0.2032 -0.2794)
							(mid -0.239121 -0.264521)
							(end -0.254 -0.2286)
						)
						(arc
							(start -0.254 0.2286)
							(mid -0.239121 0.264521)
							(end -0.2032 0.2794)
						)
						(arc
							(start 0.2032 0.2794)
							(mid 0.239121 0.264521)
							(end 0.254 0.2286)
						)
						(arc
							(start 0.254 -0.2286)
							(mid 0.239121 -0.264521)
							(end 0.2032 -0.2794)
						)
					)
					(width 0)
					(fill yes)
				)
			)
		)
		(pad "2" smd custom
			(at 0 0.4318 270)
			(size 0.127 0.127)
			(layers "F.Cu" "F.Mask" "F.Paste")
			(net "P1V0")
			(options
				(clearance outline)
				(anchor circle)
			)
			(primitives
				(gr_poly
					(pts
						(arc
							(start -0.2032 -0.2794)
							(mid -0.239121 -0.264521)
							(end -0.254 -0.2286)
						)
						(arc
							(start -0.254 0.2286)
							(mid -0.239121 0.264521)
							(end -0.2032 0.2794)
						)
						(arc
							(start 0.2032 0.2794)
							(mid 0.239121 0.264521)
							(end 0.254 0.2286)
						)
						(arc
							(start 0.254 -0.2286)
							(mid 0.239121 -0.264521)
							(end 0.2032 -0.2794)
						)
					)
					(width 0)
					(fill yes)
				)
			)
		)
	)
	(footprint ""
		(layer "F.Cu")
		(at 12.9286 -61.3156 90)
		(property "Reference" "PR45"
			(at 0 0 90)
			(layer "F.SilkS")
			(hide yes)
			(effects
				(font
					(size 1.27 1.27)
				)
			)
		)
		(property "Value" "0R2J-2-GP"
			(at 1.7907 -1.1176 90)
			(unlocked yes)
			(layer "F.Fab")
			(hide yes)
			(effects
				(font
					(size 1.016 1.016)
					(thickness 0.1524)
				)
			)
		)
		(property "Device Type" "R402H16"
			(at 1.7907 -2.6416 90)
			(unlocked yes)
			(layer "F.Fab")
			(hide yes)
			(effects
				(font
					(size 1.016 1.016)
					(thickness 0.1524)
				)
			)
		)
		(duplicate_pad_numbers_are_jumpers no)
		(fp_rect
			(start -0.381 0.8382)
			(end 0.381 -0.8382)
			(stroke
				(width 0)
				(type default)
			)
			(fill no)
			(layer "F.CrtYd")
		)
		(fp_rect
			(start -0.381 0.8382)
			(end 0.381 -0.8382)
			(stroke
				(width 0)
				(type default)
			)
			(fill no)
			(layer "F.Fab")
		)
		(pad "1" smd custom
			(at 0 -0.4318 90)
			(size 0.127 0.127)
			(layers "F.Cu" "F.Mask" "F.Paste")
			(net "TP_PVCCP_ALERT")
			(options
				(clearance outline)
				(anchor circle)
			)
			(primitives
				(gr_poly
					(pts
						(arc
							(start -0.2032 -0.2794)
							(mid -0.239121 -0.264521)
							(end -0.254 -0.2286)
						)
						(arc
							(start -0.254 0.2286)
							(mid -0.239121 0.264521)
							(end -0.2032 0.2794)
						)
						(arc
							(start 0.2032 0.2794)
							(mid 0.239121 0.264521)
							(end 0.254 0.2286)
						)
						(arc
							(start 0.254 -0.2286)
							(mid 0.239121 -0.264521)
							(end 0.2032 -0.2794)
						)
					)
					(width 0)
					(fill yes)
				)
			)
		)
		(pad "2" smd custom
			(at 0 0.4318 90)
			(size 0.127 0.127)
			(layers "F.Cu" "F.Mask" "F.Paste")
			(net "SVID_CPU_ALERT#")
			(options
				(clearance outline)
				(anchor circle)
			)
			(primitives
				(gr_poly
					(pts
						(arc
							(start -0.2032 -0.2794)
							(mid -0.239121 -0.264521)
							(end -0.254 -0.2286)
						)
						(arc
							(start -0.254 0.2286)
							(mid -0.239121 0.264521)
							(end -0.2032 0.2794)
						)
						(arc
							(start 0.2032 0.2794)
							(mid 0.239121 0.264521)
							(end 0.254 0.2286)
						)
						(arc
							(start 0.254 -0.2286)
							(mid 0.239121 -0.264521)
							(end 0.2032 -0.2794)
						)
					)
					(width 0)
					(fill yes)
				)
			)
		)
	)
	(footprint ""
		(layer "F.Cu")
		(at 55.626 -68.072 180)
		(property "Reference" "C9"
			(at 0 0 180)
			(layer "F.SilkS")
			(hide yes)
			(effects
				(font
					(size 1.27 1.27)
				)
			)
		)
		(property "Value" "SC22U6D3V5MX-2GP"
			(at 0 -4.9022 180)
			(unlocked yes)
			(layer "F.Fab")
			(hide yes)
			(effects
				(font
					(size 1.016 1.016)
					(thickness 0.1524)
				)
			)
		)
		(property "Device Type" "C805H58"
			(at 0 -6.8072 180)
			(unlocked yes)
			(layer "F.Fab")
			(hide yes)
			(effects
				(font
					(size 1.016 1.016)
					(thickness 0.1524)
				)
			)
		)
		(duplicate_pad_numbers_are_jumpers no)
		(fp_line
			(start 0.6096 0)
			(end -0.6096 0)
			(stroke
				(width 0.3048)
				(type default)
			)
			(layer "F.SilkS")
		)
		(fp_poly
			(pts
				(xy -0.9017 1.4351) (xy 0.9017 1.4351) (xy 0.9017 -1.4351) (xy -0.9017 -1.4351)
			)
			(stroke
				(width 0)
				(type default)
			)
			(fill no)
			(layer "F.CrtYd")
		)
		(fp_poly
			(pts
				(xy 0.9017 1.4351) (xy 0.9017 -1.4351) (xy -0.9017 -1.4351) (xy -0.9017 1.4351)
			)
			(stroke
				(width 0)
				(type default)
			)
			(fill no)
			(layer "F.Fab")
		)
		(pad "1" smd rect
			(at 0 -0.8382 180)
			(size 1.5494 0.9398)
			(layers "F.Cu" "F.Mask" "F.Paste")
			(net "PVNN")
		)
		(pad "2" smd rect
			(at 0 0.8382 180)
			(size 1.5494 0.9398)
			(layers "F.Cu" "F.Mask" "F.Paste")
			(net "GND")
		)
	)
	(footprint ""
		(layer "F.Cu")
		(at 11.3792 -52.7812 90)
		(property "Reference" "C58"
			(at 0 0 90)
			(layer "F.SilkS")
			(hide yes)
			(effects
				(font
					(size 1.27 1.27)
				)
			)
		)
		(property "Value" "SCD01U16V2KX-3GP"
			(at 1.1811 -2.7051 90)
			(unlocked yes)
			(layer "F.Fab")
			(hide yes)
			(effects
				(font
					(size 1.016 1.016)
					(thickness 0.1524)
				)
			)
		)
		(property "Device Type" "C402H22"
			(at 1.1811 -4.2291 90)
			(unlocked yes)
			(layer "F.Fab")
			(hide yes)
			(effects
				(font
					(size 1.016 1.016)
					(thickness 0.1524)
				)
			)
		)
		(duplicate_pad_numbers_are_jumpers no)
		(fp_rect
			(start -0.381 0.7366)
			(end 0.381 -0.7366)
			(stroke
				(width 0)
				(type default)
			)
			(fill no)
			(layer "F.CrtYd")
		)
		(fp_rect
			(start -0.381 0.7366)
			(end 0.381 -0.7366)
			(stroke
				(width 0)
				(type default)
			)
			(fill no)
			(layer "F.Fab")
		)
		(pad "1" smd custom
			(at 0 -0.4572 90)
			(size 0.1143 0.1143)
			(layers "F.Cu" "F.Mask" "F.Paste")
			(net "SATA3_RX_DN1")
			(options
				(clearance outline)
				(anchor circle)
			)
			(primitives
				(gr_poly
					(pts
						(arc
							(start -0.254 -0.1778)
							(mid -0.239121 -0.213721)
							(end -0.2032 -0.2286)
						)
						(arc
							(start 0.2032 -0.2286)
							(mid 0.239121 -0.213721)
							(end 0.254 -0.1778)
						)
						(arc
							(start 0.254 0.1778)
							(mid 0.239121 0.213721)
							(end 0.2032 0.2286)
						)
						(arc
							(start -0.2032 0.2286)
							(mid -0.239121 0.213721)
							(end -0.254 0.1778)
						)
					)
					(width 0)
					(fill yes)
				)
			)
		)
		(pad "2" smd custom
			(at 0 0.4572 90)
			(size 0.1143 0.1143)
			(layers "F.Cu" "F.Mask" "F.Paste")
			(net "P2E_CPU_NGFF_C_RX_DP12")
			(options
				(clearance outline)
				(anchor circle)
			)
			(primitives
				(gr_poly
					(pts
						(arc
							(start -0.254 -0.1778)
							(mid -0.239121 -0.213721)
							(end -0.2032 -0.2286)
						)
						(arc
							(start 0.2032 -0.2286)
							(mid 0.239121 -0.213721)
							(end 0.254 -0.1778)
						)
						(arc
							(start 0.254 0.1778)
							(mid 0.239121 0.213721)
							(end 0.2032 0.2286)
						)
						(arc
							(start -0.2032 0.2286)
							(mid -0.239121 0.213721)
							(end -0.254 0.1778)
						)
					)
					(width 0)
					(fill yes)
				)
			)
		)
	)
	(footprint ""
		(layer "F.Cu")
		(at 164.211 -45.847 180)
		(property "Reference" "R210"
			(at 0 0 180)
			(layer "F.SilkS")
			(hide yes)
			(effects
				(font
					(size 1.27 1.27)
				)
			)
		)
		(property "Value" "0R2J-2-GP"
			(at 1.7907 -1.1176 180)
			(unlocked yes)
			(layer "F.Fab")
			(hide yes)
			(effects
				(font
					(size 1.016 1.016)
					(thickness 0.1524)
				)
			)
		)
		(property "Device Type" "R402H16"
			(at 1.7907 -2.6416 180)
			(unlocked yes)
			(layer "F.Fab")
			(hide yes)
			(effects
				(font
					(size 1.016 1.016)
					(thickness 0.1524)
				)
			)
		)
		(duplicate_pad_numbers_are_jumpers no)
		(fp_rect
			(start -0.381 0.8382)
			(end 0.381 -0.8382)
			(stroke
				(width 0)
				(type default)
			)
			(fill no)
			(layer "F.CrtYd")
		)
		(fp_rect
			(start -0.381 0.8382)
			(end 0.381 -0.8382)
			(stroke
				(width 0)
				(type default)
			)
			(fill no)
			(layer "F.Fab")
		)
		(pad "1" smd custom
			(at 0 -0.4318 180)
			(size 0.127 0.127)
			(layers "F.Cu" "F.Mask" "F.Paste")
			(net "JTAG_PLD_TMS")
			(options
				(clearance outline)
				(anchor circle)
			)
			(primitives
				(gr_poly
					(pts
						(arc
							(start -0.2032 -0.2794)
							(mid -0.239121 -0.264521)
							(end -0.254 -0.2286)
						)
						(arc
							(start -0.254 0.2286)
							(mid -0.239121 0.264521)
							(end -0.2032 0.2794)
						)
						(arc
							(start 0.2032 0.2794)
							(mid 0.239121 0.264521)
							(end 0.254 0.2286)
						)
						(arc
							(start 0.254 -0.2286)
							(mid 0.239121 -0.264521)
							(end 0.2032 -0.2794)
						)
					)
					(width 0)
					(fill yes)
				)
			)
		)
		(pad "2" smd custom
			(at 0 0.4318 180)
			(size 0.127 0.127)
			(layers "F.Cu" "F.Mask" "F.Paste")
			(net "JTAG_PLD_TMS_D")
			(options
				(clearance outline)
				(anchor circle)
			)
			(primitives
				(gr_poly
					(pts
						(arc
							(start -0.2032 -0.2794)
							(mid -0.239121 -0.264521)
							(end -0.254 -0.2286)
						)
						(arc
							(start -0.254 0.2286)
							(mid -0.239121 0.264521)
							(end -0.2032 0.2794)
						)
						(arc
							(start 0.2032 0.2794)
							(mid 0.239121 0.264521)
							(end 0.254 0.2286)
						)
						(arc
							(start 0.254 -0.2286)
							(mid 0.239121 -0.264521)
							(end 0.2032 -0.2794)
						)
					)
					(width 0)
					(fill yes)
				)
			)
		)
	)
	(footprint ""
		(layer "F.Cu")
		(at 55.753 -44.577)
		(property "Reference" "R53"
			(at 0 0 0)
			(layer "F.SilkS")
			(hide yes)
			(effects
				(font
					(size 1.27 1.27)
				)
			)
		)
		(property "Value" "10KR2F-2-GP"
			(at 0.064008 -3.993896 0)
			(unlocked yes)
			(layer "F.Fab")
			(hide yes)
			(effects
				(font
					(size 1.016 1.016)
					(thickness 0.1524)
				)
			)
		)
		(property "Device Type" "R402H16"
			(at 0.064008 -5.517896 0)
			(unlocked yes)
			(layer "F.Fab")
			(hide yes)
			(effects
				(font
					(size 1.016 1.016)
					(thickness 0.1524)
				)
			)
		)
		(duplicate_pad_numbers_are_jumpers no)
		(fp_rect
			(start -0.381 0.8382)
			(end 0.381 -0.8382)
			(stroke
				(width 0)
				(type default)
			)
			(fill no)
			(layer "F.CrtYd")
		)
		(fp_rect
			(start -0.381 0.8382)
			(end 0.381 -0.8382)
			(stroke
				(width 0)
				(type default)
			)
			(fill no)
			(layer "F.Fab")
		)
		(pad "1" smd custom
			(at 0 -0.4318)
			(size 0.127 0.127)
			(layers "F.Cu" "F.Mask" "F.Paste")
			(net "P12V")
			(options
				(clearance outline)
				(anchor circle)
			)
			(primitives
				(gr_poly
					(pts
						(arc
							(start -0.2032 -0.2794)
							(mid -0.239121 -0.264521)
							(end -0.254 -0.2286)
						)
						(arc
							(start -0.254 0.2286)
							(mid -0.239121 0.264521)
							(end -0.2032 0.2794)
						)
						(arc
							(start 0.2032 0.2794)
							(mid 0.239121 0.264521)
							(end 0.254 0.2286)
						)
						(arc
							(start 0.254 -0.2286)
							(mid 0.239121 -0.264521)
							(end 0.2032 -0.2794)
						)
					)
					(width 0)
					(fill yes)
				)
			)
		)
		(pad "2" smd custom
			(at 0 0.4318)
			(size 0.127 0.127)
			(layers "F.Cu" "F.Mask" "F.Paste")
			(net "SW_P3V3_EN_LV_D")
			(options
				(clearance outline)
				(anchor circle)
			)
			(primitives
				(gr_poly
					(pts
						(arc
							(start -0.2032 -0.2794)
							(mid -0.239121 -0.264521)
							(end -0.254 -0.2286)
						)
						(arc
							(start -0.254 0.2286)
							(mid -0.239121 0.264521)
							(end -0.2032 0.2794)
						)
						(arc
							(start 0.2032 0.2794)
							(mid 0.239121 0.264521)
							(end 0.254 0.2286)
						)
						(arc
							(start 0.254 -0.2286)
							(mid 0.239121 -0.264521)
							(end 0.2032 -0.2794)
						)
					)
					(width 0)
					(fill yes)
				)
			)
		)
	)
	(footprint ""
		(layer "F.Cu")
		(at 31.877 -34.2392 90)
		(property "Reference" "R270"
			(at 0 0 90)
			(layer "F.SilkS")
			(hide yes)
			(effects
				(font
					(size 1.27 1.27)
				)
			)
		)
		(property "Value" "51R2F-2-GP"
			(at 0.064008 -3.993896 90)
			(unlocked yes)
			(layer "F.Fab")
			(hide yes)
			(effects
				(font
					(size 1.016 1.016)
					(thickness 0.1524)
				)
			)
		)
		(property "Device Type" "R402H16"
			(at 0.064008 -5.517896 90)
			(unlocked yes)
			(layer "F.Fab")
			(hide yes)
			(effects
				(font
					(size 1.016 1.016)
					(thickness 0.1524)
				)
			)
		)
		(duplicate_pad_numbers_are_jumpers no)
		(fp_rect
			(start -0.381 0.8382)
			(end 0.381 -0.8382)
			(stroke
				(width 0)
				(type default)
			)
			(fill no)
			(layer "F.CrtYd")
		)
		(fp_rect
			(start -0.381 0.8382)
			(end 0.381 -0.8382)
			(stroke
				(width 0)
				(type default)
			)
			(fill no)
			(layer "F.Fab")
		)
		(pad "1" smd custom
			(at 0 -0.4318 90)
			(size 0.127 0.127)
			(layers "F.Cu" "F.Mask" "F.Paste")
			(net "P1V0_STBY")
			(options
				(clearance outline)
				(anchor circle)
			)
			(primitives
				(gr_poly
					(pts
						(arc
							(start -0.2032 -0.2794)
							(mid -0.239121 -0.264521)
							(end -0.254 -0.2286)
						)
						(arc
							(start -0.254 0.2286)
							(mid -0.239121 0.264521)
							(end -0.2032 0.2794)
						)
						(arc
							(start 0.2032 0.2794)
							(mid 0.239121 0.264521)
							(end 0.254 0.2286)
						)
						(arc
							(start 0.254 -0.2286)
							(mid 0.239121 -0.264521)
							(end 0.2032 -0.2794)
						)
					)
					(width 0)
					(fill yes)
				)
			)
		)
		(pad "2" smd custom
			(at 0 0.4318 90)
			(size 0.127 0.127)
			(layers "F.Cu" "F.Mask" "F.Paste")
			(net "XDP_SOC_CPU_TDO")
			(options
				(clearance outline)
				(anchor circle)
			)
			(primitives
				(gr_poly
					(pts
						(arc
							(start -0.2032 -0.2794)
							(mid -0.239121 -0.264521)
							(end -0.254 -0.2286)
						)
						(arc
							(start -0.254 0.2286)
							(mid -0.239121 0.264521)
							(end -0.2032 0.2794)
						)
						(arc
							(start 0.2032 0.2794)
							(mid 0.239121 0.264521)
							(end 0.254 0.2286)
						)
						(arc
							(start 0.254 -0.2286)
							(mid 0.239121 -0.264521)
							(end 0.2032 -0.2794)
						)
					)
					(width 0)
					(fill yes)
				)
			)
		)
	)
)
